G04 ================== begin FILE IDENTIFICATION RECORD ==================*
G04 Layout Name:  12432-1.brd*
G04 Film Name:    BMASK*
G04 File Format:  Gerber RS274X*
G04 File Origin:  Cadence Allegro 16.2-S037*
G04 Origin Date:  Wed Oct 17 10:59:37 2012*
G04 *
G04 Layer:  VIA CLASS/SOLDERMASK_BOTTOM*
G04 Layer:  PIN/SOLDERMASK_BOTTOM*
G04 Layer:  PACKAGE GEOMETRY/SOLDERMASK_BOTTOM*
G04 Layer:  DRAWING FORMAT/LAYER_PCB_STORY*
G04 Layer:  DRAWING FORMAT/LAYER_SOLDER_B*
G04 Layer:  BOARD GEOMETRY/SOLDERMASK_BOTTOM*
G04 *
G04 Offset:    (0.00 0.00)*
G04 Mirror:    No*
G04 Mode:      Positive*
G04 Rotation:  0*
G04 FullContactRelief:  No*
G04 UndefLineWidth:     6.00*
G04 ================== end FILE IDENTIFICATION RECORD ====================*
%FSLAX35Y35*MOIN*%
%IR0*IPPOS*OFA0.00000B0.00000*MIA0B0*SFA1.00000B1.00000*%
%ADD16O,.103X.06*%
%ADD19R,.23X.032*%
%ADD14R,.142X.028*%
%ADD17C,.073*%
%ADD15C,.028*%
%ADD13C,.091*%
%ADD11C,.086*%
%ADD12C,.315*%
%ADD18C,.146*%
%ADD10R,.16X.16*%
%ADD20C,.02*%
%ADD21C,.006*%
G75*
%LPD*%
G75*
G36*
G01X1017308Y1433722D02*
Y1451397D01*
X991708D01*
Y1433722D01*
X1017308D01*
G37*
G36*
G01Y1453247D02*
Y1470922D01*
X991708D01*
Y1453247D01*
X1017308D01*
G37*
G36*
G01Y1473722D02*
Y1491397D01*
X991708D01*
Y1473722D01*
X1017308D01*
G37*
G36*
G01Y1493247D02*
Y1510922D01*
X991708D01*
Y1493247D01*
X1017308D01*
G37*
G36*
G01Y1513722D02*
Y1531397D01*
X991708D01*
Y1513722D01*
X1017308D01*
G37*
G36*
G01Y1553722D02*
Y1571397D01*
X991708D01*
Y1553722D01*
X1017308D01*
G37*
G36*
G01Y1533247D02*
Y1550922D01*
X991708D01*
Y1533247D01*
X1017308D01*
G37*
G36*
G01Y1573247D02*
Y1590922D01*
X991708D01*
Y1573247D01*
X1017308D01*
G37*
G36*
G01X1017307Y1593722D02*
Y1610922D01*
X991708D01*
Y1593722D01*
X1017307D01*
G37*
G54D10*
X-38666Y47522D03*
X-37468Y1947630D03*
X21499Y17050D03*
X1010999Y18550D03*
X1008999Y1968550D03*
X1073242Y50048D03*
G54D20*
G01X-87137Y-139897D02*
Y-107897D01*
G01X-75137Y-123897D02*
G02I-12000J0D01*
G01X-80287D02*
G02I-6850J0D01*
G01X-71137D02*
X-103137D01*
G01X-71137Y-139897D02*
Y-219897D01*
G01D02*
X1129963D01*
G01X-71137Y-175397D02*
X1129963D01*
G01X-71137Y-139897D02*
X1129963D01*
G01X342463D02*
Y-219897D01*
G01X479963Y-139897D02*
Y-219897D01*
G01X594963Y-139897D02*
Y-219897D01*
G01X762463Y-139897D02*
Y-219897D01*
G01X932463Y-139897D02*
Y-219897D01*
G01X1129963Y-139897D02*
Y-219897D01*
G01X1157963Y-123897D02*
G02I-12000J0D01*
G01X1152813D02*
G02I-6850J0D01*
G01X1161963D02*
X1129963D01*
G01X1145963Y-139897D02*
Y-107897D01*
G54D11*
X-38436Y23633D03*
X-36811Y1104775D03*
X-35919Y1969497D03*
X1072493Y21507D03*
X1075940Y1769358D03*
G54D21*
G01X-53190Y-209897D02*
Y-192397D01*
G01X-44894D02*
X-53190Y-203189D01*
G01X-43584Y-209897D02*
X-49479Y-198231D01*
G01X-35909Y-209897D02*
Y-192397D01*
X-25865Y-209897D01*
Y-192397D01*
G01X-13387Y-209897D02*
X-15134Y-209605D01*
X-16662Y-208439D01*
X-17972Y-206689D01*
X-18846Y-204647D01*
X-19282Y-202314D01*
Y-199980D01*
X-18846Y-197647D01*
X-17972Y-195605D01*
X-16662Y-193856D01*
X-15134Y-192689D01*
X-13387Y-192397D01*
X-11641Y-192689D01*
X-10112Y-193856D01*
X-8802Y-195605D01*
X-7928Y-197647D01*
X-7492Y-199980D01*
Y-202314D01*
X-7928Y-204647D01*
X-8802Y-206689D01*
X-10112Y-208439D01*
X-11641Y-209605D01*
X-13387Y-209897D01*
G01X-472D02*
X8698Y-192397D01*
G01X-472D02*
X8698Y-209897D01*
G01X34310D02*
Y-192397D01*
X38676D01*
X40423Y-193272D01*
X41733Y-194439D01*
X42825Y-196188D01*
X43698Y-198231D01*
X43916Y-201147D01*
X43698Y-204064D01*
X42825Y-206106D01*
X41733Y-207856D01*
X40423Y-209022D01*
X38676Y-209897D01*
X34310D01*
G01X52246D02*
Y-192397D01*
X57705D01*
X59451Y-193272D01*
X60543Y-194439D01*
X60980Y-196772D01*
X60543Y-199106D01*
X59233Y-200564D01*
X57705Y-201439D01*
X52246D01*
G01X57705D02*
X60980Y-209897D01*
G01X71493Y-192397D02*
X76733D01*
G01X74113D02*
Y-209897D01*
G01X71493D02*
X76733D01*
G01X86154Y-192397D02*
X91613Y-209897D01*
X97072Y-192397D01*
G01X113480Y-209897D02*
X104746D01*
Y-192397D01*
X113480D01*
G01X109986Y-200855D02*
X104746D01*
G01X139746Y-209897D02*
Y-192397D01*
X144986D01*
X146733Y-193272D01*
X148043Y-195314D01*
X148480Y-197647D01*
X148043Y-199980D01*
X146951Y-201730D01*
X144986Y-202606D01*
X139746D01*
G01X157246Y-192397D02*
Y-209897D01*
X165980D01*
G01X173654D02*
X179113Y-192397D01*
X184572Y-209897D01*
G01X182606Y-203772D02*
X175619D01*
G01X191591Y-209897D02*
Y-192397D01*
X201635Y-209897D01*
Y-192397D01*
G01X218480Y-209897D02*
X209746D01*
Y-192397D01*
X218480D01*
G01X214986Y-200855D02*
X209746D01*
G01X250859Y-200564D02*
X251733Y-199689D01*
X252388Y-198231D01*
X252825Y-196188D01*
X252388Y-194439D01*
X251515Y-193272D01*
X249986Y-192397D01*
X244091D01*
Y-209897D01*
X251296D01*
X252825Y-208731D01*
X253698Y-206980D01*
X254135Y-204939D01*
X253698Y-202897D01*
X252388Y-201147D01*
X250859Y-200564D01*
X244091D01*
G01X266613Y-209897D02*
X264866Y-209605D01*
X263338Y-208439D01*
X262028Y-206689D01*
X261154Y-204647D01*
X260718Y-202314D01*
Y-199980D01*
X261154Y-197647D01*
X262028Y-195605D01*
X263338Y-193856D01*
X264866Y-192689D01*
X266613Y-192397D01*
X268359Y-192689D01*
X269888Y-193856D01*
X271198Y-195605D01*
X272072Y-197647D01*
X272508Y-199980D01*
Y-202314D01*
X272072Y-204647D01*
X271198Y-206689D01*
X269888Y-208439D01*
X268359Y-209605D01*
X266613Y-209897D01*
G01X278654D02*
X284113Y-192397D01*
X289572Y-209897D01*
G01X287606Y-203772D02*
X280619D01*
G01X297246Y-209897D02*
Y-192397D01*
X302705D01*
X304451Y-193272D01*
X305543Y-194439D01*
X305980Y-196772D01*
X305543Y-199106D01*
X304233Y-200564D01*
X302705Y-201439D01*
X297246D01*
G01X302705D02*
X305980Y-209897D01*
G01X314310D02*
Y-192397D01*
X318676D01*
X320423Y-193272D01*
X321733Y-194439D01*
X322825Y-196188D01*
X323698Y-198231D01*
X323916Y-201147D01*
X323698Y-204064D01*
X322825Y-206106D01*
X321733Y-207856D01*
X320423Y-209022D01*
X318676Y-209897D01*
X314310D01*
G01X94686Y-164897D02*
Y-147397D01*
X100363Y-161980D01*
X106040Y-147397D01*
Y-164897D01*
G01X117863D02*
X116553Y-164605D01*
X115243Y-163439D01*
X114369Y-161397D01*
X113933Y-159064D01*
X114369Y-156730D01*
X115243Y-154689D01*
X116553Y-153522D01*
X117863Y-153231D01*
X119173Y-153522D01*
X120483Y-154689D01*
X121356Y-156730D01*
X121575Y-159064D01*
X121356Y-161397D01*
X120483Y-163439D01*
X119173Y-164605D01*
X117863Y-164897D01*
G01X139293Y-147397D02*
Y-164897D01*
G01Y-162273D02*
X138420Y-163731D01*
X137109Y-164605D01*
X135581Y-164897D01*
X133835Y-164314D01*
X132525Y-162856D01*
X131651Y-161106D01*
X131433Y-159064D01*
X131651Y-157022D01*
X132525Y-155272D01*
X133835Y-153814D01*
X135581Y-153231D01*
X137109Y-153522D01*
X138201Y-154106D01*
X139293Y-155272D01*
G01X149588Y-157022D02*
X156575D01*
X155920Y-154980D01*
X154828Y-153814D01*
X153300Y-153231D01*
X151771Y-153522D01*
X150461Y-154397D01*
X149588Y-156439D01*
X149151Y-158189D01*
Y-159939D01*
X149588Y-161689D01*
X150680Y-163439D01*
X151990Y-164605D01*
X153518Y-164897D01*
X155046Y-164314D01*
X156575Y-162564D01*
G01X170363Y-164897D02*
Y-147397D01*
G01X376163Y-209897D02*
Y-192397D01*
X373543Y-195897D01*
G01Y-209897D02*
X378783D01*
G01X389515Y-195314D02*
X390825Y-193564D01*
X392353Y-192689D01*
X394100Y-192397D01*
X396283Y-192980D01*
X397811Y-194439D01*
X398248Y-196188D01*
X398030Y-197939D01*
X397156Y-199397D01*
X392790Y-202314D01*
X390825Y-204355D01*
X389515Y-207273D01*
X389078Y-209897D01*
X398248D01*
G01X413783D02*
Y-192397D01*
X405704Y-204939D01*
X416622D01*
G01X423860Y-206397D02*
X425169Y-208439D01*
X426916Y-209605D01*
X428881Y-209897D01*
X430628Y-209605D01*
X432375Y-208147D01*
X433466Y-206397D01*
X433685Y-204647D01*
X433248Y-202606D01*
X431720Y-201147D01*
X430191Y-200564D01*
X428226D01*
G01X430191D02*
X431501Y-199689D01*
X432593Y-198231D01*
X433030Y-196481D01*
X432593Y-194730D01*
X431501Y-193272D01*
X429536Y-192397D01*
X427571Y-192689D01*
X425606Y-193856D01*
G01X442015Y-195314D02*
X443325Y-193564D01*
X444853Y-192689D01*
X446600Y-192397D01*
X448783Y-192980D01*
X450311Y-194439D01*
X450748Y-196188D01*
X450530Y-197939D01*
X449656Y-199397D01*
X445290Y-202314D01*
X443325Y-204355D01*
X442015Y-207273D01*
X441578Y-209897D01*
X450748D01*
G01X363046Y-164897D02*
Y-147397D01*
X368286D01*
X370033Y-148272D01*
X371343Y-150314D01*
X371780Y-152647D01*
X371343Y-154980D01*
X370251Y-156730D01*
X368286Y-157606D01*
X363046D01*
G01X389716Y-148856D02*
X388406Y-147980D01*
X386878Y-147397D01*
X385131D01*
X383166Y-148272D01*
X381638Y-149730D01*
X380546Y-151481D01*
X379673Y-154397D01*
X379454Y-157022D01*
X379891Y-159647D01*
X380546Y-161397D01*
X381856Y-163147D01*
X383385Y-164314D01*
X384913Y-164897D01*
X386441D01*
X387970Y-164314D01*
X389280Y-163439D01*
X390372Y-162273D01*
G01X404159Y-155564D02*
X405033Y-154689D01*
X405688Y-153231D01*
X406125Y-151188D01*
X405688Y-149439D01*
X404815Y-148272D01*
X403286Y-147397D01*
X397391D01*
Y-164897D01*
X404596D01*
X406125Y-163731D01*
X406998Y-161980D01*
X407435Y-159939D01*
X406998Y-157897D01*
X405688Y-156147D01*
X404159Y-155564D01*
X397391D01*
G01X413363Y-170730D02*
X426463D01*
G01X432391Y-164897D02*
Y-147397D01*
X442435Y-164897D01*
Y-147397D01*
G01X454913Y-164897D02*
X453166Y-164605D01*
X451638Y-163439D01*
X450328Y-161689D01*
X449454Y-159647D01*
X449018Y-157314D01*
Y-154980D01*
X449454Y-152647D01*
X450328Y-150605D01*
X451638Y-148856D01*
X453166Y-147689D01*
X454913Y-147397D01*
X456659Y-147689D01*
X458188Y-148856D01*
X459498Y-150605D01*
X460372Y-152647D01*
X460808Y-154980D01*
Y-157314D01*
X460372Y-159647D01*
X459498Y-161689D01*
X458188Y-163439D01*
X456659Y-164605D01*
X454913Y-164897D01*
G01X505754Y-147397D02*
X511213Y-164897D01*
X516672Y-147397D01*
G01X533080Y-164897D02*
X524346D01*
Y-147397D01*
X533080D01*
G01X529586Y-155855D02*
X524346D01*
G01X541846Y-164897D02*
Y-147397D01*
X547305D01*
X549051Y-148272D01*
X550143Y-149439D01*
X550580Y-151772D01*
X550143Y-154106D01*
X548833Y-155564D01*
X547305Y-156439D01*
X541846D01*
G01X547305D02*
X550580Y-164897D01*
G01X563713Y-165480D02*
X563276Y-165189D01*
Y-164605D01*
X563713Y-164314D01*
X564150Y-164605D01*
Y-165189D01*
X563713Y-165480D01*
G01X537463Y-209897D02*
Y-192397D01*
X534843Y-195897D01*
G01Y-209897D02*
X540083D01*
G01X630546Y-147397D02*
Y-164897D01*
X639280D01*
G01X656343D02*
Y-153231D01*
G01Y-155272D02*
X655470Y-154106D01*
X654159Y-153522D01*
X652631Y-153231D01*
X651103Y-153814D01*
X649793Y-154980D01*
X648919Y-156730D01*
X648483Y-159064D01*
X648919Y-161397D01*
X649793Y-163147D01*
X651103Y-164314D01*
X652631Y-164897D01*
X654159Y-164605D01*
X655470Y-163731D01*
X656343Y-162564D01*
G01X665328Y-170147D02*
X666638Y-170730D01*
X668385Y-170147D01*
X669476Y-168981D01*
X670350Y-167522D01*
X671659Y-162856D01*
X674498Y-153231D01*
G01X667511D02*
X671659Y-162856D01*
G01X684138Y-157022D02*
X691125D01*
X690470Y-154980D01*
X689378Y-153814D01*
X687850Y-153231D01*
X686321Y-153522D01*
X685011Y-154397D01*
X684138Y-156439D01*
X683701Y-158189D01*
Y-159939D01*
X684138Y-161689D01*
X685230Y-163439D01*
X686540Y-164605D01*
X688068Y-164897D01*
X689596Y-164314D01*
X691125Y-162564D01*
G01X701856Y-164897D02*
Y-153231D01*
G01Y-155564D02*
X702948Y-154397D01*
X704040Y-153522D01*
X705568Y-153231D01*
X706659Y-153522D01*
X707970Y-154397D01*
G01X719138Y-162856D02*
X720230Y-164022D01*
X721758Y-164897D01*
X723068D01*
X724378Y-164314D01*
X725251Y-163439D01*
X725688Y-162273D01*
X725470Y-160522D01*
X724596Y-159647D01*
X720666Y-157897D01*
X719793Y-155855D01*
X720230Y-154397D01*
X721103Y-153522D01*
X722413Y-153231D01*
X723723Y-153522D01*
X725033Y-154397D01*
G01X711917Y-200564D02*
X711043Y-199689D01*
X710388Y-198231D01*
X709951Y-196188D01*
X710388Y-194439D01*
X711261Y-193272D01*
X712790Y-192397D01*
X718685D01*
Y-209897D01*
X711480D01*
X709951Y-208731D01*
X709078Y-206980D01*
X708641Y-204939D01*
X709078Y-202897D01*
X710388Y-201147D01*
X711917Y-200564D01*
X718685D01*
G01X701840Y-209897D02*
Y-192397D01*
X696163Y-206980D01*
X690486Y-192397D01*
Y-209897D01*
G01X684122D02*
X678663Y-192397D01*
X673204Y-209897D01*
G01X675170Y-203772D02*
X682157D01*
G01X665748Y-207564D02*
X664001Y-209022D01*
X662036Y-209897D01*
X660290D01*
X658543Y-209022D01*
X657233Y-207564D01*
X656578Y-205522D01*
X657015Y-203481D01*
X658106Y-201730D01*
X660071Y-200564D01*
X662691Y-199980D01*
X664220Y-198814D01*
X664875Y-196772D01*
X664438Y-194730D01*
X663346Y-193272D01*
X661818Y-192397D01*
X660290D01*
X658761Y-192980D01*
X657451Y-194439D01*
G01X648466Y-209897D02*
Y-192397D01*
G01X640170D02*
X648466Y-203189D01*
G01X638860Y-209897D02*
X644755Y-198231D01*
G01X781410Y-164897D02*
Y-147397D01*
X785776D01*
X787523Y-148272D01*
X788833Y-149439D01*
X789925Y-151188D01*
X790798Y-153231D01*
X791016Y-156147D01*
X790798Y-159064D01*
X789925Y-161106D01*
X788833Y-162856D01*
X787523Y-164022D01*
X785776Y-164897D01*
X781410D01*
G01X800438Y-157022D02*
X807425D01*
X806770Y-154980D01*
X805678Y-153814D01*
X804150Y-153231D01*
X802621Y-153522D01*
X801311Y-154397D01*
X800438Y-156439D01*
X800001Y-158189D01*
Y-159939D01*
X800438Y-161689D01*
X801530Y-163439D01*
X802840Y-164605D01*
X804368Y-164897D01*
X805896Y-164314D01*
X807425Y-162564D01*
G01X817938Y-162856D02*
X819030Y-164022D01*
X820558Y-164897D01*
X821868D01*
X823178Y-164314D01*
X824051Y-163439D01*
X824488Y-162273D01*
X824270Y-160522D01*
X823396Y-159647D01*
X819466Y-157897D01*
X818593Y-155855D01*
X819030Y-154397D01*
X819903Y-153522D01*
X821213Y-153231D01*
X822523Y-153522D01*
X823833Y-154397D01*
G01X838713Y-153231D02*
Y-164897D01*
G01Y-148564D02*
X838276Y-148272D01*
Y-147689D01*
X838713Y-147397D01*
X839150Y-147689D01*
Y-148272D01*
X838713Y-148564D01*
G01X853156Y-169272D02*
X854685Y-170439D01*
X856431Y-170730D01*
X857959Y-170439D01*
X859270Y-168981D01*
X860143Y-166939D01*
Y-153231D01*
G01Y-155564D02*
X859270Y-154397D01*
X857959Y-153522D01*
X856431Y-153231D01*
X854685Y-153814D01*
X853593Y-154980D01*
X852719Y-157022D01*
X852283Y-159064D01*
X852501Y-160814D01*
X853375Y-162856D01*
X854685Y-164314D01*
X856431Y-164897D01*
X857741Y-164605D01*
X859270Y-163439D01*
X860143Y-162273D01*
G01X870001Y-164897D02*
Y-153231D01*
G01Y-156147D02*
X870875Y-154689D01*
X872185Y-153522D01*
X873931Y-153231D01*
X875459Y-153522D01*
X876770Y-154689D01*
X877425Y-156730D01*
Y-164897D01*
G01X887938Y-157022D02*
X894925D01*
X894270Y-154980D01*
X893178Y-153814D01*
X891650Y-153231D01*
X890121Y-153522D01*
X888811Y-154397D01*
X887938Y-156439D01*
X887501Y-158189D01*
Y-159939D01*
X887938Y-161689D01*
X889030Y-163439D01*
X890340Y-164605D01*
X891868Y-164897D01*
X893396Y-164314D01*
X894925Y-162564D01*
G01X905656Y-164897D02*
Y-153231D01*
G01Y-155564D02*
X906748Y-154397D01*
X907840Y-153522D01*
X909368Y-153231D01*
X910459Y-153522D01*
X911770Y-154397D01*
G01X825596Y-209897D02*
Y-192397D01*
X831055D01*
X832801Y-193272D01*
X833893Y-194439D01*
X834330Y-196772D01*
X833893Y-199106D01*
X832583Y-200564D01*
X831055Y-201439D01*
X825596D01*
G01X831055D02*
X834330Y-209897D01*
G01X847463D02*
X846153Y-209605D01*
X844843Y-208439D01*
X843969Y-206397D01*
X843533Y-204064D01*
X843969Y-201730D01*
X844843Y-199689D01*
X846153Y-198522D01*
X847463Y-198231D01*
X848773Y-198522D01*
X850083Y-199689D01*
X850956Y-201730D01*
X851175Y-204064D01*
X850956Y-206397D01*
X850083Y-208439D01*
X848773Y-209605D01*
X847463Y-209897D01*
G01X861033D02*
Y-192397D01*
G01Y-201147D02*
X862125Y-199397D01*
X863435Y-198522D01*
X864745Y-198231D01*
X866709Y-198814D01*
X868020Y-199980D01*
X868893Y-202022D01*
Y-204355D01*
X868456Y-206689D01*
X867583Y-208439D01*
X866055Y-209605D01*
X864745Y-209897D01*
X863435Y-209605D01*
X862125Y-208731D01*
X861033Y-207273D01*
G01X952413Y-209897D02*
Y-192397D01*
X949793Y-195897D01*
G01Y-209897D02*
X955033D01*
G01X969913Y-192397D02*
X968166Y-192980D01*
X966856Y-194439D01*
X965983Y-196188D01*
X965328Y-198522D01*
X965110Y-201147D01*
X965328Y-203772D01*
X965983Y-206106D01*
X966856Y-207856D01*
X968166Y-209314D01*
X969913Y-209897D01*
X971659Y-209314D01*
X972970Y-207856D01*
X973843Y-206106D01*
X974498Y-203772D01*
X974716Y-201147D01*
X974498Y-198522D01*
X973843Y-196188D01*
X972970Y-194439D01*
X971659Y-192980D01*
X969913Y-192397D01*
G01X983483Y-210480D02*
X991343Y-192397D01*
G01X1004913Y-209897D02*
Y-192397D01*
X1002293Y-195897D01*
G01Y-209897D02*
X1007533D01*
G01X1018265Y-202606D02*
X1019793Y-200564D01*
X1021103Y-199397D01*
X1022850Y-198814D01*
X1024378Y-199397D01*
X1025470Y-200564D01*
X1026343Y-202314D01*
X1026561Y-204355D01*
X1026343Y-206106D01*
X1025470Y-207856D01*
X1024159Y-209314D01*
X1022631Y-209897D01*
X1020885Y-209314D01*
X1019356Y-207564D01*
X1018483Y-204939D01*
X1018265Y-202022D01*
X1018701Y-198231D01*
X1019356Y-196188D01*
X1020448Y-194147D01*
X1021976Y-192689D01*
X1023505Y-192397D01*
X1025033Y-192980D01*
X1026125Y-194439D01*
G01X1035983Y-210480D02*
X1043843Y-192397D01*
G01X1053265Y-195314D02*
X1054575Y-193564D01*
X1056103Y-192689D01*
X1057850Y-192397D01*
X1060033Y-192980D01*
X1061561Y-194439D01*
X1061998Y-196188D01*
X1061780Y-197939D01*
X1060906Y-199397D01*
X1056540Y-202314D01*
X1054575Y-204355D01*
X1053265Y-207273D01*
X1052828Y-209897D01*
X1061998D01*
G01X1074913Y-192397D02*
X1073166Y-192980D01*
X1071856Y-194439D01*
X1070983Y-196188D01*
X1070328Y-198522D01*
X1070110Y-201147D01*
X1070328Y-203772D01*
X1070983Y-206106D01*
X1071856Y-207856D01*
X1073166Y-209314D01*
X1074913Y-209897D01*
X1076659Y-209314D01*
X1077970Y-207856D01*
X1078843Y-206106D01*
X1079498Y-203772D01*
X1079716Y-201147D01*
X1079498Y-198522D01*
X1078843Y-196188D01*
X1077970Y-194439D01*
X1076659Y-192980D01*
X1074913Y-192397D01*
G01X1092413Y-209897D02*
Y-192397D01*
X1089793Y-195897D01*
G01Y-209897D02*
X1095033D01*
G01X1105765Y-195314D02*
X1107075Y-193564D01*
X1108603Y-192689D01*
X1110350Y-192397D01*
X1112533Y-192980D01*
X1114061Y-194439D01*
X1114498Y-196188D01*
X1114280Y-197939D01*
X1113406Y-199397D01*
X1109040Y-202314D01*
X1107075Y-204355D01*
X1105765Y-207273D01*
X1105328Y-209897D01*
X1114498D01*
G01X1000110Y-164897D02*
Y-147397D01*
X1004476D01*
X1006223Y-148272D01*
X1007533Y-149439D01*
X1008625Y-151188D01*
X1009498Y-153231D01*
X1009716Y-156147D01*
X1009498Y-159064D01*
X1008625Y-161106D01*
X1007533Y-162856D01*
X1006223Y-164022D01*
X1004476Y-164897D01*
X1000110D01*
G01X1026343D02*
Y-153231D01*
G01Y-155272D02*
X1025470Y-154106D01*
X1024159Y-153522D01*
X1022631Y-153231D01*
X1021103Y-153814D01*
X1019793Y-154980D01*
X1018919Y-156730D01*
X1018483Y-159064D01*
X1018919Y-161397D01*
X1019793Y-163147D01*
X1021103Y-164314D01*
X1022631Y-164897D01*
X1024159Y-164605D01*
X1025470Y-163731D01*
X1026343Y-162564D01*
G01X1039913Y-147397D02*
Y-164897D01*
G01X1036856Y-153231D02*
X1042970D01*
G01X1054138Y-157022D02*
X1061125D01*
X1060470Y-154980D01*
X1059378Y-153814D01*
X1057850Y-153231D01*
X1056321Y-153522D01*
X1055011Y-154397D01*
X1054138Y-156439D01*
X1053701Y-158189D01*
Y-159939D01*
X1054138Y-161689D01*
X1055230Y-163439D01*
X1056540Y-164605D01*
X1058068Y-164897D01*
X1059596Y-164314D01*
X1061125Y-162564D01*
G54D12*
X29531Y309549D03*
Y1029510D03*
X17720Y1903132D03*
X129921Y17716D03*
X271657Y267699D03*
Y673210D03*
Y1078722D03*
Y1484234D03*
Y1889746D03*
X994098Y149588D03*
Y673210D03*
Y1068880D03*
X994093Y1889751D03*
G54D13*
X9843Y353144D03*
Y717711D03*
Y762617D03*
Y875216D03*
Y1337396D03*
Y1701963D03*
Y1746869D03*
Y1859468D03*
G54D14*
X12569Y391726D03*
Y387789D03*
Y383852D03*
Y379915D03*
Y375978D03*
Y372041D03*
Y411411D03*
Y407474D03*
Y403537D03*
Y399600D03*
Y395663D03*
Y431098D03*
Y427161D03*
Y423223D03*
Y454720D03*
Y450783D03*
Y446846D03*
Y442909D03*
Y438972D03*
Y435035D03*
Y474405D03*
Y470468D03*
Y466531D03*
Y462594D03*
Y458657D03*
Y494090D03*
Y490153D03*
Y486216D03*
Y482279D03*
Y478342D03*
Y517712D03*
Y513775D03*
Y509838D03*
Y505901D03*
Y501964D03*
Y498027D03*
Y537397D03*
Y533460D03*
Y529523D03*
Y525586D03*
Y521649D03*
Y561019D03*
Y557082D03*
Y553145D03*
Y549208D03*
Y545271D03*
Y541334D03*
Y580704D03*
Y576767D03*
Y572830D03*
Y568893D03*
Y564956D03*
Y600389D03*
Y596452D03*
Y592515D03*
Y584641D03*
Y588578D03*
Y624011D03*
Y620074D03*
Y616137D03*
Y612200D03*
Y604326D03*
Y608263D03*
Y643696D03*
Y639759D03*
Y635822D03*
Y631885D03*
Y627948D03*
Y663381D03*
Y659444D03*
Y655507D03*
Y651570D03*
Y647633D03*
Y687003D03*
Y683066D03*
Y679129D03*
Y675192D03*
Y671255D03*
Y667318D03*
Y698814D03*
Y694877D03*
Y690940D03*
X12560Y793325D03*
Y789388D03*
Y785451D03*
Y781514D03*
Y813010D03*
Y809073D03*
Y805136D03*
Y801199D03*
Y797262D03*
Y820884D03*
Y816947D03*
Y832696D03*
Y856318D03*
Y852381D03*
Y848444D03*
Y844507D03*
Y840570D03*
Y836633D03*
X12569Y1364167D03*
Y1360230D03*
Y1356293D03*
Y1383852D03*
Y1379915D03*
Y1375978D03*
Y1372041D03*
Y1368104D03*
Y1395663D03*
Y1391726D03*
Y1387789D03*
Y1427161D03*
Y1423224D03*
Y1419287D03*
Y1415350D03*
Y1411413D03*
Y1407475D03*
Y1446846D03*
Y1442909D03*
Y1438972D03*
Y1435035D03*
Y1431098D03*
Y1470468D03*
Y1466531D03*
Y1462594D03*
Y1458657D03*
Y1454720D03*
Y1450783D03*
Y1490153D03*
Y1486216D03*
Y1482279D03*
Y1478342D03*
Y1474405D03*
Y1509838D03*
Y1505901D03*
Y1501964D03*
Y1498027D03*
Y1494090D03*
Y1533460D03*
Y1529523D03*
Y1525586D03*
Y1521649D03*
Y1517712D03*
Y1513775D03*
Y1553145D03*
Y1549208D03*
Y1545271D03*
Y1541334D03*
Y1537397D03*
Y1568893D03*
Y1572830D03*
Y1564956D03*
Y1561019D03*
Y1557082D03*
Y1596452D03*
Y1588578D03*
Y1592515D03*
Y1584641D03*
Y1580704D03*
Y1576767D03*
Y1616137D03*
Y1612200D03*
Y1608263D03*
Y1604326D03*
Y1600389D03*
Y1639759D03*
Y1635822D03*
Y1631885D03*
Y1627948D03*
Y1624011D03*
Y1620074D03*
Y1659444D03*
Y1655507D03*
Y1651570D03*
Y1647633D03*
Y1643696D03*
Y1679129D03*
Y1675192D03*
Y1671255D03*
Y1667318D03*
Y1663381D03*
Y1683066D03*
X12560Y1765766D03*
Y1785451D03*
Y1781514D03*
Y1777577D03*
Y1773640D03*
Y1769703D03*
Y1805136D03*
Y1801199D03*
Y1797262D03*
Y1793325D03*
Y1789388D03*
Y1828759D03*
Y1824822D03*
Y1820885D03*
Y1816948D03*
Y1840570D03*
Y1836633D03*
Y1832696D03*
G54D15*
X17455Y1928781D03*
X33799Y553050D03*
X37849Y561450D03*
X31549Y566050D03*
X32505Y592986D03*
X32300Y597800D03*
X35766Y602721D03*
X35157Y608117D03*
X37173Y1583074D03*
X40200Y1586800D03*
X40299Y1828750D03*
X35521Y1930528D03*
X23999Y1932849D03*
X32999Y1956855D03*
X37499Y1967749D03*
X32999Y1964549D03*
X46499Y69050D03*
X57300Y452700D03*
X56500Y724500D03*
X53999Y732050D03*
X53499Y739468D03*
X43300Y806300D03*
X52299Y801450D03*
X59800Y812750D03*
X54000Y819900D03*
X44899Y836250D03*
X54799Y838050D03*
X50399Y841450D03*
X55299Y844350D03*
X61600Y850531D03*
X47200Y848431D03*
X41325Y1548747D03*
X60000Y1535500D03*
X56499Y1597069D03*
X46425Y1586470D03*
X60700Y1578962D03*
X49999Y1633069D03*
X56999Y1663550D03*
X42999Y1694569D03*
X50199Y1836052D03*
X49616Y1842667D03*
X47999Y1891050D03*
X54999Y1931550D03*
X68800Y454300D03*
X66500Y543000D03*
X73000Y548700D03*
X72300Y1018000D03*
X66000Y1020350D03*
X70999Y1025550D03*
X81999Y1541550D03*
X72599Y1546650D03*
X70099Y1540550D03*
X78400Y1566400D03*
X74600Y1557500D03*
X78462Y1574918D03*
X73499Y1613069D03*
X65000Y1697500D03*
X62399Y1776050D03*
X68999Y1773550D03*
X62300Y1789650D03*
X69499Y1918050D03*
X81999Y1934050D03*
X90000Y854500D03*
X96000Y866000D03*
X88999Y882550D03*
X89499Y892050D03*
X88005Y996217D03*
X93500Y1000300D03*
X99200Y994200D03*
X85000Y1536450D03*
X91399Y1549550D03*
X93999Y1669550D03*
X89999Y1703050D03*
X91499Y1805549D03*
X103920Y1833104D03*
X89200Y1832000D03*
X98999Y1891050D03*
X119499Y49550D03*
X116499Y82050D03*
X116999Y111050D03*
Y96050D03*
X123999Y495050D03*
X106700Y997800D03*
X109499Y1080550D03*
X111140Y1074659D03*
X120982Y1099733D03*
X109499Y1098350D03*
X104999Y1265050D03*
X113999Y1285550D03*
X105499Y1292550D03*
X118499Y1697750D03*
X116499Y1716750D03*
X121151Y1805128D03*
X120999Y1930550D03*
X145499Y49050D03*
X144999Y425550D03*
X132349Y509050D03*
X134700Y553800D03*
X137100Y570500D03*
X136783Y1335517D03*
X143500Y1323500D03*
X131599Y1714150D03*
X135899Y1722550D03*
X127499Y1708250D03*
X152499Y103550D03*
X156817Y165883D03*
X149400Y162500D03*
X157499Y502550D03*
X153000Y574000D03*
X160900Y573000D03*
X172999Y52050D03*
X178999Y88550D03*
X184200Y484400D03*
X181000Y1361000D03*
X180400Y1374000D03*
X195499Y99050D03*
X204499Y116550D03*
X194499Y109350D03*
X204699Y896610D03*
X195499Y1852550D03*
X227999Y38050D03*
X215500Y893610D03*
X229800Y1077300D03*
X223029Y1465580D03*
X221199Y1556050D03*
X225499Y1606050D03*
X229800Y1872000D03*
X218100Y1882700D03*
X214999Y1914050D03*
X215999Y1955050D03*
X210999Y1945750D03*
X241099Y95050D03*
X242000Y1069700D03*
X247252Y1826803D03*
X231999Y1918050D03*
X249499Y1924350D03*
X264499Y1968050D03*
X285999Y72550D03*
X284999Y342750D03*
X280345Y328896D03*
X285264Y749050D03*
X284764Y738315D03*
X290411Y1546462D03*
X286868Y1557582D03*
X304800Y29200D03*
X312499Y72550D03*
X315800Y104200D03*
X295999Y948550D03*
X299995Y1810554D03*
X324800Y93100D03*
X323499Y331550D03*
X331263Y742294D03*
X331499Y1940750D03*
X347328Y31519D03*
X337799Y67110D03*
X338499Y120550D03*
X342999Y169050D03*
X378428Y51119D03*
X385499Y59550D03*
X390411Y69638D03*
X392999Y337050D03*
X380999Y1618050D03*
X420499Y1335550D03*
X436499Y1836550D03*
X463499Y29550D03*
X460999Y819550D03*
X587499Y1844550D03*
X614999Y371550D03*
X636999Y914050D03*
X703999Y385550D03*
X759999Y39550D03*
X755999Y1935050D03*
X756499Y1942550D03*
X776199Y323050D03*
X772873Y330624D03*
X770999Y726750D03*
X774199Y733050D03*
X768306Y1124321D03*
X774383Y1133235D03*
X774542Y1526350D03*
X774488Y1537495D03*
X775199Y1940050D03*
X766400Y1971600D03*
X795199Y333050D03*
X789999Y340250D03*
X791999Y729350D03*
X785826Y737954D03*
X799385Y757436D03*
X782672Y1129146D03*
X795854Y1135926D03*
X788854Y1142626D03*
X787799Y1543550D03*
X797699Y1541050D03*
X790844Y1952360D03*
X799297Y1959333D03*
X822200Y258000D03*
X816500Y270600D03*
X820900Y668000D03*
X812800Y679900D03*
X815400Y1082500D03*
X806899Y1151850D03*
X811999Y1293550D03*
X804899Y1553250D03*
X825500Y1076300D03*
X833999Y1883050D03*
X835114Y1951150D03*
X849999Y44550D03*
X848499Y67550D03*
X849499Y91050D03*
X847999Y119550D03*
X864199Y321524D03*
X860499Y1192550D03*
X861849Y1383500D03*
X864799Y1532050D03*
X863838Y1542478D03*
X860085Y1715214D03*
X863699Y1902750D03*
X860799Y1917250D03*
X864414Y1944050D03*
X878499Y91550D03*
X881999Y119550D03*
X872999Y294624D03*
X869399Y288124D03*
X872599Y336224D03*
X870499Y724550D03*
X868399Y1128950D03*
X870294Y1375659D03*
X866516Y1498533D03*
X887000Y1721400D03*
X871283Y1736317D03*
X893999Y46550D03*
X890999Y73050D03*
X898999Y104550D03*
X904499Y121550D03*
X892517Y1714217D03*
X927999Y38050D03*
X918499Y107050D03*
X919542Y124007D03*
X934999Y67050D03*
X945499Y116550D03*
X951899Y45550D03*
X951499Y81050D03*
X961568Y113567D03*
G54D16*
X68898Y17047D03*
Y190275D03*
Y422559D03*
Y595787D03*
Y828071D03*
Y1001299D03*
Y1233583D03*
Y1406811D03*
Y1639095D03*
Y1812323D03*
X167323Y179803D03*
Y353031D03*
Y585315D03*
Y758543D03*
Y990827D03*
Y1164055D03*
Y1396339D03*
Y1569567D03*
Y1801851D03*
Y1975079D03*
X895669Y179803D03*
Y353031D03*
Y585315D03*
Y758543D03*
Y990827D03*
Y1164055D03*
Y1396339D03*
Y1569567D03*
Y1801851D03*
Y1975079D03*
G54D17*
X78150Y28858D03*
Y178464D03*
Y434370D03*
Y583976D03*
Y839882D03*
Y989488D03*
Y1245394D03*
Y1395000D03*
Y1650906D03*
Y1800512D03*
X158071Y191614D03*
Y341220D03*
Y597126D03*
Y746732D03*
Y1002638D03*
Y1152244D03*
Y1408150D03*
Y1557756D03*
Y1813662D03*
Y1963268D03*
X886417Y191614D03*
Y341220D03*
Y597126D03*
Y746732D03*
Y1002638D03*
Y1152244D03*
Y1408150D03*
Y1557756D03*
Y1813662D03*
Y1963268D03*
G54D18*
X1019291Y1416024D03*
Y1694212D03*
G54D19*
X1005807Y1636102D03*
Y1631102D03*
Y1626102D03*
Y1621102D03*
Y1661102D03*
Y1656102D03*
Y1651102D03*
Y1646102D03*
Y1641102D03*
Y1676102D03*
Y1671102D03*
Y1666102D03*
M02*
